(kicad_pcb
	(version 20260206)
	(generator "pcbnew")
	(generator_version "10.0")
	(general
		(thickness 1.6)
		(legacy_teardrops no)
	)
	(paper "A4")
	(title_block
		(title "04192023_DAF0TMB3IC0_F0TG_MB_C_brd_V02_OCP.brd")
		(comment 1 "Grand Teton / footprints 8069-8075 of 8354")
	)
	(layers
		(0 "F.Cu" signal "TOP")
		(4 "In1.Cu" signal "GND")
		(6 "In2.Cu" signal "IN1")
		(8 "In3.Cu" signal "GND1")
		(10 "In4.Cu" signal "IN2")
		(12 "In5.Cu" signal "GND2")
		(14 "In6.Cu" signal "IN3")
		(16 "In7.Cu" signal "GND3")
		(18 "In8.Cu" signal "VCC")
		(20 "In9.Cu" signal "VCC1")
		(22 "In10.Cu" signal "GND4")
		(24 "In11.Cu" signal "IN4")
		(26 "In12.Cu" signal "GND5")
		(28 "In13.Cu" signal "IN5")
		(30 "In14.Cu" signal "GND6")
		(32 "In15.Cu" signal "IN6")
		(34 "In16.Cu" signal "GND7")
		(2 "B.Cu" signal "BOTTOM")
		(9 "F.Adhes" user "F.Adhesive")
		(11 "B.Adhes" user "B.Adhesive")
		(13 "F.Paste" user "Package Geometry/Pastemask Top")
		(15 "B.Paste" user "Package Geometry/Pastemask Bottom")
		(5 "F.SilkS" user "Ref Des/Silkscreen Top")
		(7 "B.SilkS" user "Ref Des/Silkscreen Bottom")
		(1 "F.Mask" user "Board Geometry/Soldermask Top")
		(3 "B.Mask" user "Board Geometry/Soldermask Bottom")
		(17 "Dwgs.User" user "User.Drawings")
		(19 "Cmts.User" user "User.Comments")
		(21 "Eco1.User" user "User.Eco1")
		(23 "Eco2.User" user "User.Eco2")
		(25 "Edge.Cuts" user "Board Geometry/Outline")
		(27 "Margin" user)
		(31 "F.CrtYd" user "Package Geometry/Place Bound Top")
		(29 "B.CrtYd" user "Package Geometry/Place Bound Bottom")
		(35 "F.Fab" user "Ref Des/Assembly Top")
		(33 "B.Fab" user "Ref Des/Assembly Bottom")
	)
	(footprint ""
		(layer "B.Cu")
		(at 49.882044 -349.386398 -90)
		(property "Reference" "PR280"
			(at 0 0 90)
			(layer "B.SilkS")
			(hide yes)
			(effects
				(font
					(size 1.27 1.27)
				)
				(justify mirror)
			)
		)
		(property "Value" ""
			(at 0 0 90)
			(layer "B.Fab")
			(effects
				(font
					(size 1.27 1.27)
				)
				(justify mirror)
			)
		)
		(duplicate_pad_numbers_are_jumpers no)
		(fp_line
			(start -0.7874 0.4064)
			(end 0.7874 0.4064)
			(stroke
				(width 0.1524)
				(type default)
			)
			(layer "B.SilkS")
		)
		(fp_line
			(start 0.7874 0.4064)
			(end 0.7874 -0.4064)
			(stroke
				(width 0.1524)
				(type default)
			)
			(layer "B.SilkS")
		)
		(fp_line
			(start -0.7874 -0.4064)
			(end -0.7874 0.4064)
			(stroke
				(width 0.1524)
				(type default)
			)
			(layer "B.SilkS")
		)
		(fp_line
			(start 0.7874 -0.4064)
			(end -0.7874 -0.4064)
			(stroke
				(width 0.1524)
				(type default)
			)
			(layer "B.SilkS")
		)
		(fp_line
			(start -0.67945 0.3048)
			(end -0.120396 0.3048)
			(stroke
				(width 0.1)
				(type default)
			)
			(layer "B.Fab")
		)
		(fp_line
			(start -0.120396 0.3048)
			(end -0.120396 0.2794)
			(stroke
				(width 0.1)
				(type default)
			)
			(layer "B.Fab")
		)
		(fp_line
			(start 0.12065 0.3048)
			(end 0.67945 0.3048)
			(stroke
				(width 0.1)
				(type default)
			)
			(layer "B.Fab")
		)
		(fp_line
			(start 0.67945 0.3048)
			(end 0.67945 -0.305054)
			(stroke
				(width 0.1)
				(type default)
			)
			(layer "B.Fab")
		)
		(fp_line
			(start -0.120396 0.2794)
			(end 0.12065 0.2794)
			(stroke
				(width 0.1)
				(type default)
			)
			(layer "B.Fab")
		)
		(fp_line
			(start 0.12065 0.2794)
			(end 0.12065 0.3048)
			(stroke
				(width 0.1)
				(type default)
			)
			(layer "B.Fab")
		)
		(fp_line
			(start -0.12065 -0.2794)
			(end -0.12065 -0.3048)
			(stroke
				(width 0.1)
				(type default)
			)
			(layer "B.Fab")
		)
		(fp_line
			(start 0.12065 -0.2794)
			(end -0.12065 -0.2794)
			(stroke
				(width 0.1)
				(type default)
			)
			(layer "B.Fab")
		)
		(fp_line
			(start -0.67945 -0.3048)
			(end -0.67945 0.3048)
			(stroke
				(width 0.1)
				(type default)
			)
			(layer "B.Fab")
		)
		(fp_line
			(start -0.12065 -0.3048)
			(end -0.67945 -0.3048)
			(stroke
				(width 0.1)
				(type default)
			)
			(layer "B.Fab")
		)
		(fp_line
			(start 0.12065 -0.305054)
			(end 0.12065 -0.2794)
			(stroke
				(width 0.1)
				(type default)
			)
			(layer "B.Fab")
		)
		(fp_line
			(start 0.67945 -0.305054)
			(end 0.12065 -0.305054)
			(stroke
				(width 0.1)
				(type default)
			)
			(layer "B.Fab")
		)
		(pad "1" smd circle
			(at 0.40005 0 90)
			(size 0 0)
			(layers "B.Cu" "B.Mask" "B.Paste")
			(net "PVDDIO_P1_VOS1")
		)
		(pad "2" smd circle
			(at -0.40005 0 90)
			(size 0 0)
			(layers "B.Cu" "B.Mask" "B.Paste")
			(net "PVDDIO_P1")
		)
	)
	(footprint ""
		(layer "B.Cu")
		(at 419.140894 -427.594014 180)
		(property "Reference" "R841"
			(at 0 0 0)
			(layer "B.SilkS")
			(hide yes)
			(effects
				(font
					(size 1.27 1.27)
				)
				(justify mirror)
			)
		)
		(property "Value" ""
			(at 0 0 0)
			(layer "B.Fab")
			(effects
				(font
					(size 1.27 1.27)
				)
				(justify mirror)
			)
		)
		(duplicate_pad_numbers_are_jumpers no)
		(fp_line
			(start 0.32512 0.175006)
			(end 0.32512 -0.175006)
			(stroke
				(width 0.1)
				(type default)
			)
			(layer "B.Fab")
		)
		(fp_line
			(start 0.32512 -0.175006)
			(end -0.32512 -0.175006)
			(stroke
				(width 0.1)
				(type default)
			)
			(layer "B.Fab")
		)
		(fp_line
			(start -0.32512 0.175006)
			(end 0.32512 0.175006)
			(stroke
				(width 0.1)
				(type default)
			)
			(layer "B.Fab")
		)
		(fp_line
			(start -0.32512 -0.175006)
			(end -0.32512 0.175006)
			(stroke
				(width 0.1)
				(type default)
			)
			(layer "B.Fab")
		)
		(pad "1" smd rect
			(at 0.2667 0)
			(size 0.3048 0.381)
			(layers "B.Cu" "B.Mask" "B.Paste")
			(net "P1V8_CPU0_RT_1D")
		)
		(pad "2" smd rect
			(at -0.2667 0 180)
			(size 0.3048 0.381)
			(layers "B.Cu" "B.Mask" "B.Paste")
			(net "SMB_RT_CPU0_P2_ROM_R_SCL")
		)
	)
	(footprint ""
		(layer "B.Cu")
		(at 363.873288 -267.52931)
		(property "Reference" "C2204"
			(at 0 0 0)
			(layer "B.SilkS")
			(hide yes)
			(effects
				(font
					(size 1.27 1.27)
				)
				(justify mirror)
			)
		)
		(property "Value" ""
			(at 0 0 0)
			(layer "B.Fab")
			(effects
				(font
					(size 1.27 1.27)
				)
				(justify mirror)
			)
		)
		(duplicate_pad_numbers_are_jumpers no)
		(fp_line
			(start -0.7874 -0.4064)
			(end -0.7874 0.4064)
			(stroke
				(width 0.1524)
				(type default)
			)
			(layer "B.SilkS")
		)
		(fp_line
			(start -0.7874 0.4064)
			(end 0.7874 0.4064)
			(stroke
				(width 0.1524)
				(type default)
			)
			(layer "B.SilkS")
		)
		(fp_line
			(start 0.7874 -0.4064)
			(end -0.7874 -0.4064)
			(stroke
				(width 0.1524)
				(type default)
			)
			(layer "B.SilkS")
		)
		(fp_line
			(start 0.7874 0.4064)
			(end 0.7874 -0.4064)
			(stroke
				(width 0.1524)
				(type default)
			)
			(layer "B.SilkS")
		)
		(fp_line
			(start -0.67945 -0.3048)
			(end -0.67945 0.3048)
			(stroke
				(width 0.1)
				(type default)
			)
			(layer "B.Fab")
		)
		(fp_line
			(start -0.67945 0.3048)
			(end -0.120396 0.3048)
			(stroke
				(width 0.1)
				(type default)
			)
			(layer "B.Fab")
		)
		(fp_line
			(start -0.12065 -0.3048)
			(end -0.67945 -0.3048)
			(stroke
				(width 0.1)
				(type default)
			)
			(layer "B.Fab")
		)
		(fp_line
			(start -0.12065 -0.2794)
			(end -0.12065 -0.3048)
			(stroke
				(width 0.1)
				(type default)
			)
			(layer "B.Fab")
		)
		(fp_line
			(start -0.120396 0.2794)
			(end 0.12065 0.2794)
			(stroke
				(width 0.1)
				(type default)
			)
			(layer "B.Fab")
		)
		(fp_line
			(start -0.120396 0.3048)
			(end -0.120396 0.2794)
			(stroke
				(width 0.1)
				(type default)
			)
			(layer "B.Fab")
		)
		(fp_line
			(start 0.12065 -0.305054)
			(end 0.12065 -0.2794)
			(stroke
				(width 0.1)
				(type default)
			)
			(layer "B.Fab")
		)
		(fp_line
			(start 0.12065 -0.2794)
			(end -0.12065 -0.2794)
			(stroke
				(width 0.1)
				(type default)
			)
			(layer "B.Fab")
		)
		(fp_line
			(start 0.12065 0.2794)
			(end 0.12065 0.3048)
			(stroke
				(width 0.1)
				(type default)
			)
			(layer "B.Fab")
		)
		(fp_line
			(start 0.12065 0.3048)
			(end 0.67945 0.3048)
			(stroke
				(width 0.1)
				(type default)
			)
			(layer "B.Fab")
		)
		(fp_line
			(start 0.67945 -0.305054)
			(end 0.12065 -0.305054)
			(stroke
				(width 0.1)
				(type default)
			)
			(layer "B.Fab")
		)
		(fp_line
			(start 0.67945 0.3048)
			(end 0.67945 -0.305054)
			(stroke
				(width 0.1)
				(type default)
			)
			(layer "B.Fab")
		)
		(pad "1" smd circle
			(at 0.40005 0 180)
			(size 0 0)
			(layers "B.Cu" "B.Mask" "B.Paste")
			(net "PVDDCR_CPU1_P0")
		)
		(pad "2" smd circle
			(at -0.40005 0 180)
			(size 0 0)
			(layers "B.Cu" "B.Mask" "B.Paste")
			(net "GND")
		)
	)
	(footprint ""
		(layer "B.Cu")
		(at 463.172556 -389.126222 -90)
		(property "Reference" "PR6557"
			(at 0 0 90)
			(layer "B.SilkS")
			(hide yes)
			(effects
				(font
					(size 1.27 1.27)
				)
				(justify mirror)
			)
		)
		(property "Value" ""
			(at 0 0 90)
			(layer "B.Fab")
			(effects
				(font
					(size 1.27 1.27)
				)
				(justify mirror)
			)
		)
		(duplicate_pad_numbers_are_jumpers no)
		(fp_line
			(start -1.2954 0.5842)
			(end 1.2954 0.5842)
			(stroke
				(width 0.1524)
				(type default)
			)
			(layer "B.SilkS")
		)
		(fp_line
			(start 1.2954 0.5842)
			(end 1.2954 -0.5842)
			(stroke
				(width 0.1524)
				(type default)
			)
			(layer "B.SilkS")
		)
		(fp_line
			(start -1.2954 -0.5842)
			(end -1.2954 0.5842)
			(stroke
				(width 0.1524)
				(type default)
			)
			(layer "B.SilkS")
		)
		(fp_line
			(start 1.2954 -0.5842)
			(end -1.2954 -0.5842)
			(stroke
				(width 0.1524)
				(type default)
			)
			(layer "B.SilkS")
		)
		(fp_line
			(start -0.8636 0.4572)
			(end 0.8636 0.4572)
			(stroke
				(width 0.1)
				(type default)
			)
			(layer "B.Fab")
		)
		(fp_line
			(start 0.8636 0.4572)
			(end 0.8636 0.4318)
			(stroke
				(width 0.1)
				(type default)
			)
			(layer "B.Fab")
		)
		(fp_line
			(start 0.8636 0.4318)
			(end 0.8636 0.4064)
			(stroke
				(width 0.1)
				(type default)
			)
			(layer "B.Fab")
		)
		(fp_line
			(start -1.1938 0.4064)
			(end -0.8636 0.4064)
			(stroke
				(width 0.1)
				(type default)
			)
			(layer "B.Fab")
		)
		(fp_line
			(start -0.8636 0.4064)
			(end -0.8636 0.4572)
			(stroke
				(width 0.1)
				(type default)
			)
			(layer "B.Fab")
		)
		(fp_line
			(start 0.8636 0.4064)
			(end 1.1938 0.4064)
			(stroke
				(width 0.1)
				(type default)
			)
			(layer "B.Fab")
		)
		(fp_line
			(start 1.1938 0.4064)
			(end 1.1938 -0.406654)
			(stroke
				(width 0.1)
				(type default)
			)
			(layer "B.Fab")
		)
		(fp_line
			(start -1.1938 -0.406654)
			(end -1.1938 0.4064)
			(stroke
				(width 0.1)
				(type default)
			)
			(layer "B.Fab")
		)
		(fp_line
			(start -0.8636 -0.406654)
			(end -1.1938 -0.406654)
			(stroke
				(width 0.1)
				(type default)
			)
			(layer "B.Fab")
		)
		(fp_line
			(start 0.8636 -0.406654)
			(end 0.8636 -0.4572)
			(stroke
				(width 0.1)
				(type default)
			)
			(layer "B.Fab")
		)
		(fp_line
			(start 1.1938 -0.406654)
			(end 0.8636 -0.406654)
			(stroke
				(width 0.1)
				(type default)
			)
			(layer "B.Fab")
		)
		(fp_line
			(start -0.8636 -0.4572)
			(end -0.8636 -0.406654)
			(stroke
				(width 0.1)
				(type default)
			)
			(layer "B.Fab")
		)
		(fp_line
			(start 0.8636 -0.4572)
			(end -0.8636 -0.4572)
			(stroke
				(width 0.1)
				(type default)
			)
			(layer "B.Fab")
		)
		(pad "1" smd rect
			(at 0.7366 0 180)
			(size 0.7112 0.8128)
			(layers "B.Cu" "B.Mask" "B.Paste")
			(net "P0V9_CPU0_RT_2D")
		)
		(pad "2" smd rect
			(at -0.7366 0 180)
			(size 0.7112 0.8128)
			(layers "B.Cu" "B.Mask" "B.Paste")
			(net "GND")
		)
	)
	(footprint ""
		(layer "B.Cu")
		(at 407.010362 -416.899344 90)
		(property "Reference" "C6619"
			(at 0 0 90)
			(layer "B.SilkS")
			(hide yes)
			(effects
				(font
					(size 1.27 1.27)
				)
				(justify mirror)
			)
		)
		(property "Value" ""
			(at 0 0 90)
			(layer "B.Fab")
			(effects
				(font
					(size 1.27 1.27)
				)
				(justify mirror)
			)
		)
		(duplicate_pad_numbers_are_jumpers no)
		(fp_line
			(start 0.299974 -0.150114)
			(end -0.299974 -0.150114)
			(stroke
				(width 0.1)
				(type default)
			)
			(layer "B.Fab")
		)
		(fp_line
			(start -0.299974 -0.150114)
			(end -0.299974 0.150114)
			(stroke
				(width 0.1)
				(type default)
			)
			(layer "B.Fab")
		)
		(fp_line
			(start 0.299974 0.150114)
			(end 0.299974 -0.150114)
			(stroke
				(width 0.1)
				(type default)
			)
			(layer "B.Fab")
		)
		(fp_line
			(start -0.299974 0.150114)
			(end 0.299974 0.150114)
			(stroke
				(width 0.1)
				(type default)
			)
			(layer "B.Fab")
		)
		(pad "1" smd rect
			(at 0.2667 0 270)
			(size 0.3048 0.381)
			(layers "B.Cu" "B.Mask" "B.Paste")
			(net "P5E_CPU0_P3_TX_BUF_C_DP<11>")
		)
		(pad "2" smd rect
			(at -0.2667 0 270)
			(size 0.3048 0.381)
			(layers "B.Cu" "B.Mask" "B.Paste")
			(net "P5E_CPU0_P3_TX_BUF_DP<11>")
		)
	)
	(footprint ""
		(layer "B.Cu")
		(at 399.518124 -344.850212 90)
		(property "Reference" "C5000"
			(at 0 0 90)
			(layer "B.SilkS")
			(hide yes)
			(effects
				(font
					(size 1.27 1.27)
				)
				(justify mirror)
			)
		)
		(property "Value" ""
			(at 0 0 90)
			(layer "B.Fab")
			(effects
				(font
					(size 1.27 1.27)
				)
				(justify mirror)
			)
		)
		(duplicate_pad_numbers_are_jumpers no)
		(fp_line
			(start 0.7874 -0.4064)
			(end -0.7874 -0.4064)
			(stroke
				(width 0.1524)
				(type default)
			)
			(layer "B.SilkS")
		)
		(fp_line
			(start -0.7874 -0.4064)
			(end -0.7874 0.4064)
			(stroke
				(width 0.1524)
				(type default)
			)
			(layer "B.SilkS")
		)
		(fp_line
			(start 0.7874 0.4064)
			(end 0.7874 -0.4064)
			(stroke
				(width 0.1524)
				(type default)
			)
			(layer "B.SilkS")
		)
		(fp_line
			(start -0.7874 0.4064)
			(end 0.7874 0.4064)
			(stroke
				(width 0.1524)
				(type default)
			)
			(layer "B.SilkS")
		)
		(fp_line
			(start 0.67945 -0.305054)
			(end 0.12065 -0.305054)
			(stroke
				(width 0.1)
				(type default)
			)
			(layer "B.Fab")
		)
		(fp_line
			(start 0.12065 -0.305054)
			(end 0.12065 -0.2794)
			(stroke
				(width 0.1)
				(type default)
			)
			(layer "B.Fab")
		)
		(fp_line
			(start -0.12065 -0.3048)
			(end -0.67945 -0.3048)
			(stroke
				(width 0.1)
				(type default)
			)
			(layer "B.Fab")
		)
		(fp_line
			(start -0.67945 -0.3048)
			(end -0.67945 0.3048)
			(stroke
				(width 0.1)
				(type default)
			)
			(layer "B.Fab")
		)
		(fp_line
			(start 0.12065 -0.2794)
			(end -0.12065 -0.2794)
			(stroke
				(width 0.1)
				(type default)
			)
			(layer "B.Fab")
		)
		(fp_line
			(start -0.12065 -0.2794)
			(end -0.12065 -0.3048)
			(stroke
				(width 0.1)
				(type default)
			)
			(layer "B.Fab")
		)
		(fp_line
			(start 0.12065 0.2794)
			(end 0.12065 0.3048)
			(stroke
				(width 0.1)
				(type default)
			)
			(layer "B.Fab")
		)
		(fp_line
			(start -0.120396 0.2794)
			(end 0.12065 0.2794)
			(stroke
				(width 0.1)
				(type default)
			)
			(layer "B.Fab")
		)
		(fp_line
			(start 0.67945 0.3048)
			(end 0.67945 -0.305054)
			(stroke
				(width 0.1)
				(type default)
			)
			(layer "B.Fab")
		)
		(fp_line
			(start 0.12065 0.3048)
			(end 0.67945 0.3048)
			(stroke
				(width 0.1)
				(type default)
			)
			(layer "B.Fab")
		)
		(fp_line
			(start -0.120396 0.3048)
			(end -0.120396 0.2794)
			(stroke
				(width 0.1)
				(type default)
			)
			(layer "B.Fab")
		)
		(fp_line
			(start -0.67945 0.3048)
			(end -0.120396 0.3048)
			(stroke
				(width 0.1)
				(type default)
			)
			(layer "B.Fab")
		)
		(pad "1" smd circle
			(at 0.40005 0 270)
			(size 0 0)
			(layers "B.Cu" "B.Mask" "B.Paste")
			(net "FM_BIOS_POST_CMPLT_BUF_N")
		)
		(pad "2" smd circle
			(at -0.40005 0 270)
			(size 0 0)
			(layers "B.Cu" "B.Mask" "B.Paste")
			(net "GND")
		)
	)
	(footprint ""
		(layer "B.Cu")
		(at 177.673 -100.294948 -90)
		(property "Reference" "R1329"
			(at 0 0 90)
			(layer "B.SilkS")
			(hide yes)
			(effects
				(font
					(size 1.27 1.27)
				)
				(justify mirror)
			)
		)
		(property "Value" ""
			(at 0 0 90)
			(layer "B.Fab")
			(effects
				(font
					(size 1.27 1.27)
				)
				(justify mirror)
			)
		)
		(duplicate_pad_numbers_are_jumpers no)
		(fp_line
			(start -0.7874 0.4064)
			(end 0.7874 0.4064)
			(stroke
				(width 0.1524)
				(type default)
			)
			(layer "B.SilkS")
		)
		(fp_line
			(start 0.7874 0.4064)
			(end 0.7874 -0.4064)
			(stroke
				(width 0.1524)
				(type default)
			)
			(layer "B.SilkS")
		)
		(fp_line
			(start -0.7874 -0.4064)
			(end -0.7874 0.4064)
			(stroke
				(width 0.1524)
				(type default)
			)
			(layer "B.SilkS")
		)
		(fp_line
			(start 0.7874 -0.4064)
			(end -0.7874 -0.4064)
			(stroke
				(width 0.1524)
				(type default)
			)
			(layer "B.SilkS")
		)
		(fp_line
			(start -0.67945 0.3048)
			(end -0.120396 0.3048)
			(stroke
				(width 0.1)
				(type default)
			)
			(layer "B.Fab")
		)
		(fp_line
			(start -0.120396 0.3048)
			(end -0.120396 0.2794)
			(stroke
				(width 0.1)
				(type default)
			)
			(layer "B.Fab")
		)
		(fp_line
			(start 0.12065 0.3048)
			(end 0.67945 0.3048)
			(stroke
				(width 0.1)
				(type default)
			)
			(layer "B.Fab")
		)
		(fp_line
			(start 0.67945 0.3048)
			(end 0.67945 -0.305054)
			(stroke
				(width 0.1)
				(type default)
			)
			(layer "B.Fab")
		)
		(fp_line
			(start -0.120396 0.2794)
			(end 0.12065 0.2794)
			(stroke
				(width 0.1)
				(type default)
			)
			(layer "B.Fab")
		)
		(fp_line
			(start 0.12065 0.2794)
			(end 0.12065 0.3048)
			(stroke
				(width 0.1)
				(type default)
			)
			(layer "B.Fab")
		)
		(fp_line
			(start -0.12065 -0.2794)
			(end -0.12065 -0.3048)
			(stroke
				(width 0.1)
				(type default)
			)
			(layer "B.Fab")
		)
		(fp_line
			(start 0.12065 -0.2794)
			(end -0.12065 -0.2794)
			(stroke
				(width 0.1)
				(type default)
			)
			(layer "B.Fab")
		)
		(fp_line
			(start -0.67945 -0.3048)
			(end -0.67945 0.3048)
			(stroke
				(width 0.1)
				(type default)
			)
			(layer "B.Fab")
		)
		(fp_line
			(start -0.12065 -0.3048)
			(end -0.67945 -0.3048)
			(stroke
				(width 0.1)
				(type default)
			)
			(layer "B.Fab")
		)
		(fp_line
			(start 0.12065 -0.305054)
			(end 0.12065 -0.2794)
			(stroke
				(width 0.1)
				(type default)
			)
			(layer "B.Fab")
		)
		(fp_line
			(start 0.67945 -0.305054)
			(end 0.12065 -0.305054)
			(stroke
				(width 0.1)
				(type default)
			)
			(layer "B.Fab")
		)
		(pad "1" smd circle
			(at 0.40005 0 90)
			(size 0 0)
			(layers "B.Cu" "B.Mask" "B.Paste")
			(net "E1S_0_P3V3_P12V_ADC_R_ALERT")
		)
		(pad "2" smd circle
			(at -0.40005 0 90)
			(size 0 0)
			(layers "B.Cu" "B.Mask" "B.Paste")
			(net "E1S_0_P3V3_P12V_ADC_ALERT")
		)
	)
)
